# S9S_MB_2U (Grand Teton) — schematic netlist excerpt (pin names and nets, part order shuffled) for the footprints in the layout excerpt that follows; sources: Cadence DE-HDL packaged netlist, KiCad conversion of 03242023_DA0F0TMBIJ0_F0T_Motherboard_J_brd_V01_OCP.brd

PR287  Q_RES  2.2 1% CHIP  pkg 0402LF  page 288 : A = PVCCIN_CPU1_PVCC ; B = PVCCIN_CPU1_VDD8
R899  Q_RES  33.2 1% CHIP  pkg 0402LF  page 114 : A = PWRGD_CHD_CPU1_DIMM1 ; B = PWRGD_FAIL_CPU1_CD

(kicad_pcb
	(version 20260206)
	(generator "pcbnew")
	(generator_version "10.0")
	(general
		(thickness 1.6)
		(legacy_teardrops no)
	)
	(paper "A4")
	(title_block
		(title "03242023_DA0F0TMBIJ0_F0T_Motherboard_J_brd_V01_OCP.brd")
		(comment 1 "Grand Teton / footprints 5410-5411 of 6105")
	)
	(layers
		(0 "F.Cu" signal "TOP")
		(4 "In1.Cu" signal "GND")
		(6 "In2.Cu" signal "IN1")
		(8 "In3.Cu" signal "GND1")
		(10 "In4.Cu" signal "IN2")
		(12 "In5.Cu" signal "GND2")
		(14 "In6.Cu" signal "IN3")
		(16 "In7.Cu" signal "GND3")
		(18 "In8.Cu" signal "VCC")
		(20 "In9.Cu" signal "VCC1")
		(22 "In10.Cu" signal "GND4")
		(24 "In11.Cu" signal "IN4")
		(26 "In12.Cu" signal "GND5")
		(28 "In13.Cu" signal "IN5")
		(30 "In14.Cu" signal "GND6")
		(32 "In15.Cu" signal "IN6")
		(34 "In16.Cu" signal "GND7")
		(2 "B.Cu" signal "BOTTOM")
		(9 "F.Adhes" user "F.Adhesive")
		(11 "B.Adhes" user "B.Adhesive")
		(13 "F.Paste" user "Package Geometry/Pastemask Top")
		(15 "B.Paste" user "Package Geometry/Pastemask Bottom")
		(5 "F.SilkS" user "Ref Des/Silkscreen Top")
		(7 "B.SilkS" user "Ref Des/Silkscreen Bottom")
		(1 "F.Mask" user "Board Geometry/Soldermask Top")
		(3 "B.Mask" user "Board Geometry/Soldermask Bottom")
		(17 "Dwgs.User" user "User.Drawings")
		(19 "Cmts.User" user "User.Comments")
		(21 "Eco1.User" user "User.Eco1")
		(23 "Eco2.User" user "User.Eco2")
		(25 "Edge.Cuts" user "Board Geometry/Outline")
		(27 "Margin" user)
		(31 "F.CrtYd" user "Package Geometry/Place Bound Top")
		(29 "B.CrtYd" user "Package Geometry/Place Bound Bottom")
		(35 "F.Fab" user "Ref Des/Assembly Top")
		(33 "B.Fab" user "Ref Des/Assembly Bottom")
	)
	(footprint ""
		(layer "B.Cu")
		(at 12.217146 -319.268856 180)
		(property "Reference" "R899"
			(at 0 0 0)
			(layer "B.SilkS")
			(hide yes)
			(effects
				(font
					(size 1.27 1.27)
				)
				(justify mirror)
			)
		)
		(property "Value" ""
			(at 0 0 0)
			(layer "B.Fab")
			(effects
				(font
					(size 1.27 1.27)
				)
				(justify mirror)
			)
		)
		(duplicate_pad_numbers_are_jumpers no)
		(fp_line
			(start 0.7874 0.4064)
			(end 0.7874 -0.4064)
			(stroke
				(width 0.1524)
				(type default)
			)
			(layer "B.SilkS")
		)
		(fp_line
			(start 0.7874 -0.4064)
			(end -0.7874 -0.4064)
			(stroke
				(width 0.1524)
				(type default)
			)
			(layer "B.SilkS")
		)
		(fp_line
			(start -0.7874 0.4064)
			(end 0.7874 0.4064)
			(stroke
				(width 0.1524)
				(type default)
			)
			(layer "B.SilkS")
		)
		(fp_line
			(start -0.7874 -0.4064)
			(end -0.7874 0.4064)
			(stroke
				(width 0.1524)
				(type default)
			)
			(layer "B.SilkS")
		)
		(fp_line
			(start 0.67945 0.3048)
			(end 0.67945 -0.305054)
			(stroke
				(width 0.1)
				(type default)
			)
			(layer "B.Fab")
		)
		(fp_line
			(start 0.67945 -0.305054)
			(end 0.12065 -0.305054)
			(stroke
				(width 0.1)
				(type default)
			)
			(layer "B.Fab")
		)
		(fp_line
			(start 0.12065 0.3048)
			(end 0.67945 0.3048)
			(stroke
				(width 0.1)
				(type default)
			)
			(layer "B.Fab")
		)
		(fp_line
			(start 0.12065 0.2794)
			(end 0.12065 0.3048)
			(stroke
				(width 0.1)
				(type default)
			)
			(layer "B.Fab")
		)
		(fp_line
			(start 0.12065 -0.2794)
			(end -0.12065 -0.2794)
			(stroke
				(width 0.1)
				(type default)
			)
			(layer "B.Fab")
		)
		(fp_line
			(start 0.12065 -0.305054)
			(end 0.12065 -0.2794)
			(stroke
				(width 0.1)
				(type default)
			)
			(layer "B.Fab")
		)
		(fp_line
			(start -0.120396 0.3048)
			(end -0.120396 0.2794)
			(stroke
				(width 0.1)
				(type default)
			)
			(layer "B.Fab")
		)
		(fp_line
			(start -0.120396 0.2794)
			(end 0.12065 0.2794)
			(stroke
				(width 0.1)
				(type default)
			)
			(layer "B.Fab")
		)
		(fp_line
			(start -0.12065 -0.2794)
			(end -0.12065 -0.3048)
			(stroke
				(width 0.1)
				(type default)
			)
			(layer "B.Fab")
		)
		(fp_line
			(start -0.12065 -0.3048)
			(end -0.67945 -0.3048)
			(stroke
				(width 0.1)
				(type default)
			)
			(layer "B.Fab")
		)
		(fp_line
			(start -0.67945 0.3048)
			(end -0.120396 0.3048)
			(stroke
				(width 0.1)
				(type default)
			)
			(layer "B.Fab")
		)
		(fp_line
			(start -0.67945 -0.3048)
			(end -0.67945 0.3048)
			(stroke
				(width 0.1)
				(type default)
			)
			(layer "B.Fab")
		)
		(pad "1" smd circle
			(at 0.40005 0)
			(size 0 0)
			(layers "B.Cu" "B.Mask" "B.Paste")
			(net "PWRGD_CHD_CPU1_DIMM1")
		)
		(pad "2" smd circle
			(at -0.40005 0)
			(size 0 0)
			(layers "B.Cu" "B.Mask" "B.Paste")
			(net "PWRGD_FAIL_CPU1_CD")
		)
	)
	(footprint ""
		(layer "B.Cu")
		(at 135.489442 -343.927938 -90)
		(property "Reference" "PR287"
			(at 0 0 90)
			(layer "B.SilkS")
			(hide yes)
			(effects
				(font
					(size 1.27 1.27)
				)
				(justify mirror)
			)
		)
		(property "Value" ""
			(at 0 0 90)
			(layer "B.Fab")
			(effects
				(font
					(size 1.27 1.27)
				)
				(justify mirror)
			)
		)
		(duplicate_pad_numbers_are_jumpers no)
		(fp_line
			(start -0.7874 0.4064)
			(end 0.7874 0.4064)
			(stroke
				(width 0.1524)
				(type default)
			)
			(layer "B.SilkS")
		)
		(fp_line
			(start 0.7874 0.4064)
			(end 0.7874 -0.4064)
			(stroke
				(width 0.1524)
				(type default)
			)
			(layer "B.SilkS")
		)
		(fp_line
			(start -0.7874 -0.4064)
			(end -0.7874 0.4064)
			(stroke
				(width 0.1524)
				(type default)
			)
			(layer "B.SilkS")
		)
		(fp_line
			(start 0.7874 -0.4064)
			(end -0.7874 -0.4064)
			(stroke
				(width 0.1524)
				(type default)
			)
			(layer "B.SilkS")
		)
		(fp_line
			(start -0.67945 0.3048)
			(end -0.120396 0.3048)
			(stroke
				(width 0.1)
				(type default)
			)
			(layer "B.Fab")
		)
		(fp_line
			(start -0.120396 0.3048)
			(end -0.120396 0.2794)
			(stroke
				(width 0.1)
				(type default)
			)
			(layer "B.Fab")
		)
		(fp_line
			(start 0.12065 0.3048)
			(end 0.67945 0.3048)
			(stroke
				(width 0.1)
				(type default)
			)
			(layer "B.Fab")
		)
		(fp_line
			(start 0.67945 0.3048)
			(end 0.67945 -0.305054)
			(stroke
				(width 0.1)
				(type default)
			)
			(layer "B.Fab")
		)
		(fp_line
			(start -0.120396 0.2794)
			(end 0.12065 0.2794)
			(stroke
				(width 0.1)
				(type default)
			)
			(layer "B.Fab")
		)
		(fp_line
			(start 0.12065 0.2794)
			(end 0.12065 0.3048)
			(stroke
				(width 0.1)
				(type default)
			)
			(layer "B.Fab")
		)
		(fp_line
			(start -0.12065 -0.2794)
			(end -0.12065 -0.3048)
			(stroke
				(width 0.1)
				(type default)
			)
			(layer "B.Fab")
		)
		(fp_line
			(start 0.12065 -0.2794)
			(end -0.12065 -0.2794)
			(stroke
				(width 0.1)
				(type default)
			)
			(layer "B.Fab")
		)
		(fp_line
			(start -0.67945 -0.3048)
			(end -0.67945 0.3048)
			(stroke
				(width 0.1)
				(type default)
			)
			(layer "B.Fab")
		)
		(fp_line
			(start -0.12065 -0.3048)
			(end -0.67945 -0.3048)
			(stroke
				(width 0.1)
				(type default)
			)
			(layer "B.Fab")
		)
		(fp_line
			(start 0.12065 -0.305054)
			(end 0.12065 -0.2794)
			(stroke
				(width 0.1)
				(type default)
			)
			(layer "B.Fab")
		)
		(fp_line
			(start 0.67945 -0.305054)
			(end 0.12065 -0.305054)
			(stroke
				(width 0.1)
				(type default)
			)
			(layer "B.Fab")
		)
		(pad "1" smd circle
			(at 0.40005 0 90)
			(size 0 0)
			(layers "B.Cu" "B.Mask" "B.Paste")
			(net "PVCCIN_CPU1_PVCC")
		)
		(pad "2" smd circle
			(at -0.40005 0 90)
			(size 0 0)
			(layers "B.Cu" "B.Mask" "B.Paste")
			(net "PVCCIN_CPU1_VDD8")
		)
	)
)
